FILE_TYPE = CONNECTIVITY;
{Allegro Design Entry HDL 17.4-2019 S026 (4007227) 1/17/2022}
"PAGE_NUMBER" = 408;
0"NC";
1"P1V8_CPU0_RT_1D\g";
2"GND\g";
3"GND\g";
4"GND\g";
5"GND\g";
6"GND\g";
7"P1V8_CPU0_RT_1D\g";
8"GND\g";
9"P1V8_CPU0_RT_1D\g";
10"GND\g";
11"GND\g";
12"P1V8_CPU0_RT_1D\g";
13"GND\g";
14"GND\g";
15"GND\g";
16"SMB_RT_CPU0_P1_ROM_MUX_1D_SCL";
17"SMB_RT_CPU0_P1_ROM_MUX_1D_R_SCL";
18"SMB_RT_CPU0_P1_ROM_MUX_1D_SDA";
19"SMB_RT_CPU0_P1_ROM_MUX_1D_R_SDA";
20"RT_CPU0_P1_SCAN_MODE";
21"RST_RT_CPU0_P1_RESET_N";
22"P1V8_CPU0_RT_1D\g";
23"GND\g";
24"GND\g";
25"P1V8_CPU0_RT_1D\g";
26"P1V8_CPU0_RT_1D\g";
27"JTAG_TCK_RT_CPU0_P1";
28"JTAG_TDO_RT_CPU0_P1";
29"JTAG_TMS_RT_CPU0_P1";
30"JTAG_TDI_RT_CPU0_P1";
31"RST_RT_CPU0_P1_RESET_R_N";
32"RST_RT_CPU0_P1_PERST_R_N";
33"RT_CPU0_P1_SCAN_MODE";
34"RT_CPU0_P1_ADDR3";
35"TEST1_RT_CPU0_P1";
36"TEST0_RT_CPU0_P1";
37"CLK_100M_RETIMER_CPU0_P1_R_DP";
38"CLK_100M_RETIMER_CPU0_P1_R_DN";
39"CLK_100M_RETIMER_CPU0_P1_DP";
40"CLK_100M_RETIMER_CPU0_P1_DN";
41"TEST2_RT_CPU0_P1";
42"MODE_RT_CPU0_P1";
43"SMB_RT_CPU0_P1_R_SDA";
44"GPIO2_RT_CPU0_P1";
45"TEST1_RT_CPU0_P1";
46"RT_CPU0_P1_ADDR1";
47"RST_RT_CPU0_P1_PERST_R_N";
48"RT_CPU0_P1_ADDR2";
49"RT_CPU0_P1_ADDR3";
50"RST_RT_CPU0_P1_RESET_R_N";
51"RT_CPU0_P1_ADDR1";
52"SMB_RT_CPU0_P1_R2_SDA";
53"SMB_RT_CPU0_P1_R2_SCL";
54"SMB_RT_CPU0_P1_R_SCL";
55"TEST0_RT_CPU0_P1";
56"TEST2_RT_CPU0_P1";
57"GPIO3_RT_CPU0_P1";
58"JTAG_TEST_MODE_RT_CPU0_P1";
59"RT_CPU0_P1_ADDR2";
60"RXDET_BYP_RT_CPU0_P1";
61"GPIO3_RT_CPU0_P1";
62"GPIO2_RT_CPU0_P1";
63"CLKREQ_RT_CPU0_P1_N";
64"RST_RT_CPU0_P1_PERST_N";
65"JTAG_TRST_RT_CPU0_P1_N";
66"JTAG_TDI_RT_CPU0_P1";
67"JTAG_TMS_RT_CPU0_P1";
68"JTAG_TDO_RT_CPU0_P1";
69"JTAG_TCK_RT_CPU0_P1";
70"JTAG_TEST_MODE_RT_CPU0_P1";
71"MODE_RT_CPU0_P1";
72"RXDET_BYP_RT_CPU0_P1";
%"Q_RES"
"2","(-8950,6000)","0","pure_quanta","I10";
;
LOCATION"R1027"
$SEC"1"
CDS_SEC"1"
TOLERANCE"5%"
PACK_TYPE"0201LF"
MATERIAL"EMPTY"
WATTAGE"1/20W"
VALUE"4.7K"
CDS_LIB"pure_quanta"
PART_NUMBER"CS24701JE04";
"A"
$PN"1"26;
"B"
$PN"2"44;
%"P1V0"
"1","(-1275,4100)","0","pure_quanta_power","I100";
;
HDL_POWER"P1V8_CPU0_RT_1D"
CDS_LIB"pure_quanta_power";
"A"1;
%"Q_RES"
"2","(-8975,3450)","0","pure_quanta","I102";
;
LOCATION"R1022"
$SEC"1"
CDS_SEC"1"
PACK_TYPE"0201LF"
MATERIAL"CHIP"
TOLERANCE"1%"
VALUE"200"
WATTAGE"1/20W"
CDS_LIB"pure_quanta"
PART_NUMBER"CS12001FE12";
"A"
$PN"1"20;
"B"
$PN"2"5;
%"Q_RES"
"2","(-8325,6000)","0","pure_quanta","I11";
;
LOCATION"R1030"
$SEC"1"
CDS_SEC"1"
VALUE"4.7K"
MATERIAL"EMPTY"
PACK_TYPE"0201LF"
WATTAGE"1/20W"
TOLERANCE"5%"
CDS_LIB"pure_quanta"
PART_NUMBER"CS24701JE04";
"A"
$PN"1"26;
"B"
$PN"2"36;
%"Q_RES"
"2","(-1650,1350)","0","pure_quanta","I115";
;
LOCATION"R1470"
$SEC"1"
CDS_SEC"1"
PACK_TYPE"0201LF"
VALUE"4.7K"
TOLERANCE"5%"
WATTAGE"1/20W"
MATERIAL"EMPTY"
CDS_LIB"pure_quanta"
PART_NUMBER"CS24701JE04";
"A"
$PN"1"25;
"B"
$PN"2"30;
%"Q_RES"
"2","(-1375,1350)","0","pure_quanta","I116";
;
LOCATION"R1471"
$SEC"1"
CDS_SEC"1"
MATERIAL"EMPTY"
WATTAGE"1/20W"
TOLERANCE"5%"
VALUE"4.7K"
PACK_TYPE"0201LF"
CDS_LIB"pure_quanta"
PART_NUMBER"CS24701JE04";
"A"
$PN"1"25;
"B"
$PN"2"29;
%"Q_RES"
"2","(-825,725)","0","pure_quanta","I119";
;
LOCATION"R1392"
$SEC"1"
CDS_SEC"1"
TOLERANCE"5%"
VALUE"4.7K"
WATTAGE"1/20W"
MATERIAL"CHIP"
PACK_TYPE"0201LF"
CDS_LIB"pure_quanta"
PART_NUMBER"CS24701JE04";
"A"
$PN"1"27;
"B"
$PN"2"2;
%"P1V0"
"1","(-8950,6400)","0","pure_quanta_power","I12";
;
HDL_POWER"P1V8_CPU0_RT_1D"
CDS_LIB"pure_quanta_power";
"A"26;
%"GND"
"1","(-825,425)","0","pure_quanta_power","I120";
;
SIZE"1B"
BOM_COST"MEM"
CDS_LIB"pure_quanta_power"
HDL_POWER"GND";
"A<SIZE-1..0>\NAC"2;
%"Q_RES"
"2","(-1100,1350)","0","pure_quanta","I121";
;
LOCATION"R1472"
$SEC"1"
CDS_SEC"1"
PACK_TYPE"0201LF"
MATERIAL"EMPTY"
WATTAGE"1/20W"
TOLERANCE"1%"
VALUE"1K"
CDS_LIB"pure_quanta"
PART_NUMBER"CS21001FE07";
"A"
$PN"1"25;
"B"
$PN"2"28;
%"Q_RES"
"2","(-825,1375)","0","pure_quanta","I122";
;
LOCATION"R1473"
$SEC"1"
CDS_SEC"1"
PACK_TYPE"0201LF"
MATERIAL"EMPTY"
VALUE"4.7K"
TOLERANCE"5%"
WATTAGE"1/20W"
CDS_LIB"pure_quanta"
PART_NUMBER"CS24701JE04";
"A"
$PN"1"25;
"B"
$PN"2"27;
%"P1V0"
"1","(-825,1675)","0","pure_quanta_power","I123";
;
HDL_POWER"P1V8_CPU0_RT_1D"
CDS_LIB"pure_quanta_power";
"A"25;
%"Q_RES"
"1","(-6600,1050)","0","pure_quanta","I15";
;
LOCATION"R612"
SEC"1"
PACK_TYPE"0201LF"
MATERIAL"CHIP"
CDS_LIB"pure_quanta"
TOLERANCE"5%"
VALUE"0"
WATTAGE"1/20W"
SEC_TYPE"0201LF"
PART_NUMBER"CS00001JE10";
"B"
$PN"2"40;
"A"
$PN"1"38;
%"UNIVERSAL_GND"
"1","(-6300,400)","0","pure_quanta_power","I16";
;
CDS_LIB"pure_quanta_power"
HDL_POWER"GND";
"A"3;
%"UNIVERSAL_GND"
"1","(-6150,400)","0","pure_quanta_power","I17";
;
CDS_LIB"pure_quanta_power"
HDL_POWER"GND";
"A"4;
%"Q_RES"
"2","(-6300,725)","2","pure_quanta","I18";
;
LOCATION"R629"
$SEC"1"
CDS_SEC"1"
MATERIAL"EMPTY"
PACK_TYPE"0201LF"
TOLERANCE"1%"
VALUE"51.1"
WATTAGE"1/20W"
CDS_LIB"pure_quanta"
PART_NUMBER"CS05111FE00";
"A"
$PN"1"40;
"B"
$PN"2"3;
%"Q_RES"
"2","(-6150,725)","0","pure_quanta","I19";
;
LOCATION"R630"
$SEC"1"
CDS_SEC"1"
PACK_TYPE"0201LF"
MATERIAL"EMPTY"
WATTAGE"1/20W"
TOLERANCE"1%"
VALUE"51.1"
CDS_LIB"pure_quanta"
PART_NUMBER"CS05111FE00";
"A"
$PN"1"39;
"B"
$PN"2"4;
%"Q_RES"
"1","(-6600,1200)","0","pure_quanta","I20";
;
LOCATION"R611"
SEC"1"
TOLERANCE"5%"
VALUE"0"
WATTAGE"1/20W"
PACK_TYPE"0201LF"
MATERIAL"CHIP"
CDS_LIB"pure_quanta"
SEC_TYPE"0201LF"
PART_NUMBER"CS00001JE10";
"B"
$PN"2"39;
"A"
$PN"1"37;
%"Q_RES"
"1","(-6325,1550)","0","pure_quanta","I21";
;
LOCATION"R677"
$SEC"1"
CDS_SEC"1"
CDS_LIB"pure_quanta"
MATERIAL"CHIP"
WATTAGE"1/20W"
PACK_TYPE"0201LF"
VALUE"49.9"
TOLERANCE"1%"
PART_NUMBER"CS04991FE06";
"B"
$PN"2"19;
"A"
$PN"1"18;
%"Q_RES"
"1","(-6325,1650)","0","pure_quanta","I22";
;
LOCATION"R676"
$SEC"1"
CDS_SEC"1"
PACK_TYPE"0201LF"
WATTAGE"1/20W"
MATERIAL"CHIP"
VALUE"49.9"
TOLERANCE"1%"
CDS_LIB"pure_quanta"
PART_NUMBER"CS04991FE06";
"B"
$PN"2"17;
"A"
$PN"1"16;
%"Q_RES"
"1","(-6350,2800)","0","pure_quanta","I29";
;
LOCATION"R1026"
$SEC"1"
CDS_SEC"1"
CDS_LIB"pure_quanta"
PACK_TYPE"0201LF"
MATERIAL"CHIP"
TOLERANCE"5%"
VALUE"0"
WATTAGE"1/20W"
PART_NUMBER"CS00001JE10";
"B"
$PN"2"52;
"A"
$PN"1"43;
%"UNIVERSAL_GND"
"1","(-8975,3175)","0","pure_quanta_power","I3";
;
CDS_LIB"pure_quanta_power"
HDL_POWER"GND";
"A"5;
%"Q_RES"
"1","(-6350,2900)","0","pure_quanta","I30";
;
LOCATION"R1025"
$SEC"1"
CDS_SEC"1"
MATERIAL"CHIP"
PACK_TYPE"0201LF"
WATTAGE"1/20W"
TOLERANCE"5%"
VALUE"0"
CDS_LIB"pure_quanta"
PART_NUMBER"CS00001JE10";
"B"
$PN"2"53;
"A"
$PN"1"54;
%"Q_RES"
"2","(-8025,5025)","0","pure_quanta","I36";
;
LOCATION"R1033"
$SEC"1"
CDS_SEC"1"
TOLERANCE"5%"
PACK_TYPE"0201LF"
MATERIAL"CHIP"
WATTAGE"1/20W"
VALUE"4.7K"
CDS_LIB"pure_quanta"
PART_NUMBER"CS24701JE04";
"A"
$PN"1"45;
"B"
$PN"2"24;
%"Q_RES"
"2","(-7725,5025)","0","pure_quanta","I37";
;
LOCATION"R1035"
$SEC"1"
CDS_SEC"1"
PACK_TYPE"0201LF"
VALUE"4.7K"
TOLERANCE"5%"
WATTAGE"1/20W"
MATERIAL"CHIP"
CDS_LIB"pure_quanta"
PART_NUMBER"CS24701JE04";
"A"
$PN"1"41;
"B"
$PN"2"24;
%"UNIVERSAL_GND"
"1","(-7425,4550)","0","pure_quanta_power","I38";
;
CDS_LIB"pure_quanta_power"
HDL_POWER"GND";
"A"24;
%"Q_RES"
"2","(-7425,5000)","0","pure_quanta","I39";
;
LOCATION"R1037"
$SEC"1"
CDS_SEC"1"
TOLERANCE"5%"
MATERIAL"CHIP"
WATTAGE"1/20W"
PACK_TYPE"0201LF"
VALUE"4.7K"
CDS_LIB"pure_quanta"
PART_NUMBER"CS24701JE04";
"A"
$PN"1"58;
"B"
$PN"2"24;
%"Q_RES"
"2","(-8025,5950)","0","pure_quanta","I40";
;
LOCATION"R1032"
$SEC"1"
CDS_SEC"1"
PACK_TYPE"0201LF"
MATERIAL"EMPTY"
TOLERANCE"5%"
VALUE"4.7K"
WATTAGE"1/20W"
CDS_LIB"pure_quanta"
PART_NUMBER"CS24701JE04";
"A"
$PN"1"26;
"B"
$PN"2"45;
%"Q_RES"
"2","(-7725,5975)","0","pure_quanta","I41";
;
LOCATION"R1034"
$SEC"1"
CDS_SEC"1"
WATTAGE"1/20W"
MATERIAL"EMPTY"
VALUE"4.7K"
TOLERANCE"5%"
PACK_TYPE"0201LF"
CDS_LIB"pure_quanta"
PART_NUMBER"CS24701JE04";
"A"
$PN"1"26;
"B"
$PN"2"41;
%"Q_RES"
"2","(-7425,6000)","0","pure_quanta","I42";
;
LOCATION"R1024"
$SEC"1"
CDS_SEC"1"
MATERIAL"EMPTY"
WATTAGE"1/20W"
VALUE"4.7K"
TOLERANCE"5%"
PACK_TYPE"0201LF"
CDS_LIB"pure_quanta"
PART_NUMBER"CS24701JE04";
"A"
$PN"1"26;
"B"
$PN"2"58;
%"UNIVERSAL_GND"
"1","(-5025,5200)","0","pure_quanta_power","I49";
;
CDS_LIB"pure_quanta_power"
HDL_POWER"GND";
"A"6;
%"Q_RES"
"2","(-8975,4125)","0","pure_quanta","I5";
;
LOCATION"R1021"
$SEC"1"
CDS_SEC"1"
VALUE"4.7K"
WATTAGE"1/20W"
PACK_TYPE"0201LF"
TOLERANCE"5%"
MATERIAL"EMPTY"
CDS_LIB"pure_quanta"
PART_NUMBER"CS24701JE04";
"A"
$PN"1"9;
"B"
$PN"2"20;
%"Q_RES"
"2","(-5025,5550)","0","pure_quanta","I50";
;
LOCATION"R1006"
$SEC"1"
CDS_SEC"1"
MATERIAL"EMPTY"
WATTAGE"1/20W"
TOLERANCE"5%"
VALUE"4.7K"
PACK_TYPE"0201LF"
CDS_LIB"pure_quanta"
PART_NUMBER"CS24701JE04";
"A"
$PN"1"42;
"B"
$PN"2"6;
%"Q_RES"
"2","(-5025,6075)","0","pure_quanta","I51";
;
LOCATION"R1039"
$SEC"1"
CDS_SEC"1"
PACK_TYPE"0201LF"
MATERIAL"CHIP"
TOLERANCE"5%"
VALUE"4.7K"
WATTAGE"1/20W"
CDS_LIB"pure_quanta"
PART_NUMBER"CS24701JE04";
"A"
$PN"1"7;
"B"
$PN"2"42;
%"P1V0"
"1","(-5025,6400)","0","pure_quanta_power","I53";
;
HDL_POWER"P1V8_CPU0_RT_1D"
CDS_LIB"pure_quanta_power";
"A"7;
%"UNIVERSAL_GND"
"1","(-3325,1700)","1","pure_quanta_power","I54";
;
CDS_LIB"pure_quanta_power"
HDL_POWER"GND";
"A"8;
%"Q_RES"
"1","(-2575,2100)","0","pure_quanta","I55";
;
LOCATION"R1012"
$SEC"1"
CDS_SEC"1"
PACK_TYPE"0201LF"
VALUE"0"
CDS_LIB"pure_quanta"
MATERIAL"CHIP"
TOLERANCE"5%"
WATTAGE"1/20W"
PART_NUMBER"CS00001JE10";
"B"
$PN"2"31;
"A"
$PN"1"21;
%"Q_RES"
"1","(-2575,2200)","0","pure_quanta","I56";
;
LOCATION"R1004"
SEC"1"
PACK_TYPE"0201LF"
VALUE"0"
WATTAGE"1/20W"
TOLERANCE"5%"
MATERIAL"CHIP"
SEC_TYPE"0201LF"
CDS_LIB"pure_quanta"
PART_NUMBER"CS00001JE10";
"B"
$PN"2"32;
"A"
$PN"1"64;
%"P1V0"
"1","(-8975,4450)","0","pure_quanta_power","I6";
;
HDL_POWER"P1V8_CPU0_RT_1D"
CDS_LIB"pure_quanta_power";
"A"9;
%"UNIVERSAL_GND"
"1","(-3475,4800)","0","pure_quanta_power","I63";
;
CDS_LIB"pure_quanta_power"
HDL_POWER"GND";
"A"23;
%"Q_RES"
"2","(-3475,5225)","0","pure_quanta","I64";
;
LOCATION"R1014"
$SEC"1"
CDS_SEC"1"
VALUE"1K"
WATTAGE"1/20W"
PACK_TYPE"0201LF"
MATERIAL"EMPTY"
TOLERANCE"1%"
CDS_LIB"pure_quanta"
PART_NUMBER"CS21001FE07";
"A"
$PN"1"49;
"B"
$PN"2"23;
%"Q_RES"
"2","(-3175,5225)","0","pure_quanta","I65";
;
LOCATION"R1016"
$SEC"1"
CDS_SEC"1"
MATERIAL"CHIP"
VALUE"20K"
PACK_TYPE"0201LF"
TOLERANCE"1%"
WATTAGE"1/20W"
CDS_LIB"pure_quanta"
PART_NUMBER"CS32001FE00";
"A"
$PN"1"48;
"B"
$PN"2"23;
%"Q_RES"
"2","(-3475,6000)","0","pure_quanta","I66";
;
LOCATION"R1013"
$SEC"1"
CDS_SEC"1"
TOLERANCE"1%"
VALUE"1K"
WATTAGE"1/20W"
MATERIAL"CHIP"
PACK_TYPE"0201LF"
CDS_LIB"pure_quanta"
PART_NUMBER"CS21001FE07";
"A"
$PN"1"22;
"B"
$PN"2"49;
%"Q_RES"
"2","(-3175,6000)","0","pure_quanta","I67";
;
LOCATION"R1015"
$SEC"1"
CDS_SEC"1"
WATTAGE"1/20W"
VALUE"1K"
MATERIAL"EMPTY"
TOLERANCE"1%"
PACK_TYPE"0201LF"
CDS_LIB"pure_quanta"
PART_NUMBER"CS21001FE07";
"A"
$PN"1"22;
"B"
$PN"2"48;
%"Q_RES"
"2","(-2825,5225)","0","pure_quanta","I68";
;
LOCATION"R1018"
$SEC"1"
CDS_SEC"1"
TOLERANCE"1%"
VALUE"1K"
PACK_TYPE"0201LF"
MATERIAL"CHIP"
WATTAGE"1/20W"
CDS_LIB"pure_quanta"
PART_NUMBER"CS21001FE07";
"A"
$PN"1"46;
"B"
$PN"2"23;
%"Q_RES"
"2","(-2825,5975)","0","pure_quanta","I69";
;
LOCATION"R1017"
$SEC"1"
CDS_SEC"1"
WATTAGE"1/20W"
TOLERANCE"1%"
VALUE"1K"
MATERIAL"EMPTY"
PACK_TYPE"0201LF"
CDS_LIB"pure_quanta"
PART_NUMBER"CS21001FE07";
"A"
$PN"1"22;
"B"
$PN"2"46;
%"Q_RES"
"2","(-8950,5050)","0","pure_quanta","I7";
;
LOCATION"R1028"
$SEC"1"
CDS_SEC"1"
VALUE"10K"
TOLERANCE"1%"
WATTAGE"1/20W"
MATERIAL"CHIP"
PACK_TYPE"0201LF"
CDS_LIB"pure_quanta"
PART_NUMBER"CS31001FE17";
"A"
$PN"1"44;
"B"
$PN"2"24;
%"P1V0"
"1","(-3475,6425)","0","pure_quanta_power","I70";
;
HDL_POWER"P1V8_CPU0_RT_1D"
CDS_LIB"pure_quanta_power";
"A"22;
%"GND"
"1","(-1300,4875)","0","pure_quanta_power","I71";
;
CDS_LIB"pure_quanta_power"
BOM_COST"MEM"
SIZE"1B"
HDL_POWER"GND";
"A<SIZE-1..0>\NAC"10;
%"GND"
"1","(-1475,4850)","0","pure_quanta_power","I72";
;
BOM_COST"MEM"
SIZE"1B"
CDS_LIB"pure_quanta_power"
HDL_POWER"GND";
"A<SIZE-1..0>\NAC"11;
%"Q_RES"
"2","(-1300,5225)","0","pure_quanta","I73";
;
LOCATION"R1019"
$SEC"1"
CDS_SEC"1"
MATERIAL"CHIP"
TOLERANCE"1%"
PACK_TYPE"0201LF"
VALUE"10K"
WATTAGE"1/20W"
CDS_LIB"pure_quanta"
PART_NUMBER"CS31001FE17";
"A"
$PN"1"47;
"B"
$PN"2"10;
%"Q_RES"
"2","(-1475,5225)","2","pure_quanta","I74";
;
LOCATION"R1020"
$SEC"1"
CDS_SEC"1"
VALUE"10K"
MATERIAL"CHIP"
PACK_TYPE"0201LF"
WATTAGE"1/20W"
TOLERANCE"1%"
CDS_LIB"pure_quanta"
PART_NUMBER"CS31001FE17";
"A"
$PN"1"50;
"B"
$PN"2"11;
%"Q_RES"
"2","(-1475,6050)","2","pure_quanta","I78";
;
LOCATION"R1023"
$SEC"1"
CDS_SEC"1"
TOLERANCE"5%"
VALUE"4.7K"
MATERIAL"EMPTY"
PACK_TYPE"0201LF"
WATTAGE"1/20W"
CDS_LIB"pure_quanta"
PART_NUMBER"CS24701JE04";
"A"
$PN"1"12;
"B"
$PN"2"50;
%"Q_RES"
"2","(-8650,5050)","0","pure_quanta","I8";
;
LOCATION"R1029"
$SEC"1"
CDS_SEC"1"
WATTAGE"1/20W"
PACK_TYPE"0201LF"
MATERIAL"CHIP"
TOLERANCE"1%"
VALUE"10K"
CDS_LIB"pure_quanta"
PART_NUMBER"CS31001FE17";
"A"
$PN"1"57;
"B"
$PN"2"24;
%"P1V0"
"1","(-1475,6300)","0","pure_quanta_power","I81";
;
HDL_POWER"P1V8_CPU0_RT_1D"
CDS_LIB"pure_quanta_power";
"A"12;
%"PT5161LRS"
"3","(-4375,2350)","0","pure_quanta","I83";
;
LOCATION"U6011"
$SEC"3"
CDS_SEC"3"
PART_TYPE"SMLF"
VALUE"PT5161LRS"
MATERIAL"IC"
NEEDS_NO_SIZE"TRUE"
CDS_LMAN_SYM_OUTLINE"-500,1450,450,-1400"
CDS_LIB"pure_quanta"
PART_NUMBER"AJ051610U03";
"EE_DAT"
$PN"FJ3"19;
"EE_CLK"
$PN"FF5"17;
"CLKREQ_N \B"
$PN"G35"63;
"TEST2"
$PN"FF30"56;
"TEST1"
$PN"FF27"35;
"TEST0"
$PN"FF24"55;
"T_SENSE"
$PN"E30"8;
"SMBDAT"
$PN"B28"52;
"SMBCLK"
$PN"B31"53;
"SMB_ADDR3"
$PN"B25"34;
"SMB_ADDR2"
$PN"B23"59;
"SMB_ADDR1"
$PN"F34"51;
"SCAN_MODE"
$PN"FF33"33;
"RXDET_BYP"
$PN"E11"72;
"RESET_N \B"
$PN"FF11"21;
"REFCLKP"
$PN"FJ16"39;
"REFCLKN"
$PN"FF18"40;
"REFCLK_OUTP"
$PN"B16"0;
"REFCLK_OUTN"
$PN"E18"0;
"PERST_N \B"
$PN"F2"64;
"MODE"
$PN"FJ9"71;
"JTAG_TRST_N \B"
$PN"E8"65;
"JTAG_TMS"
$PN"B12"67;
"JTAG_TEST_MODE"
$PN"FF8"70;
"JTAG_TDO"
$PN"B9"68;
"JTAG_TDI"
$PN"B6"66;
"JTAG_TCK"
$PN"B3"69;
"INT_N \B"
$PN"FJ31"0;
"GPIO3"
$PN"FJ28"61;
"GPIO2"
$PN"FJ25"62;
"GPIO1"
$PN"FJ23"0;
"GPIO0"
$PN"FJ6"0;
%"Q_RES"
"1","(-2700,3250)","0","pure_quanta","I84";
;
LOCATION"R1391"
$SEC"1"
CDS_SEC"1"
VALUE"1K"
MATERIAL"CHIP"
PACK_TYPE"0201LF"
TOLERANCE"1%"
WATTAGE"1/20W"
CDS_LIB"pure_quanta"
PART_NUMBER"CS21001FE07";
"B"
$PN"2"13;
"A"
$PN"1"65;
%"UNIVERSAL_GND"
"1","(-1950,3250)","1","pure_quanta_power","I88";
;
CDS_LIB"pure_quanta_power"
HDL_POWER"GND";
"A"13;
%"Q_RES"
"2","(-8325,5050)","0","pure_quanta","I9";
;
LOCATION"R1031"
$SEC"1"
CDS_SEC"1"
PACK_TYPE"0201LF"
MATERIAL"CHIP"
WATTAGE"1/20W"
VALUE"4.7K"
TOLERANCE"5%"
CDS_LIB"pure_quanta"
PART_NUMBER"CS24701JE04";
"A"
$PN"1"36;
"B"
$PN"2"24;
%"Q_RES"
"1","(-2675,2300)","0","pure_quanta","I94";
;
LOCATION"R1395"
$SEC"1"
CDS_SEC"1"
PACK_TYPE"0201LF"
VALUE"4.7K"
MATERIAL"CHIP"
WATTAGE"1/20W"
TOLERANCE"5%"
CDS_LIB"pure_quanta"
PART_NUMBER"CS24701JE04";
"B"
$PN"2"14;
"A"
$PN"1"63;
%"UNIVERSAL_GND"
"1","(-1950,2300)","1","pure_quanta_power","I95";
;
CDS_LIB"pure_quanta_power"
HDL_POWER"GND";
"A"14;
%"GND"
"1","(-1275,2775)","0","pure_quanta_power","I97";
;
CDS_LIB"pure_quanta_power"
SIZE"1B"
BOM_COST"MEM"
HDL_POWER"GND";
"A<SIZE-1..0>\NAC"15;
%"Q_RES"
"2","(-1275,3175)","0","pure_quanta","I98";
;
LOCATION"R1398"
$SEC"1"
CDS_SEC"1"
MATERIAL"CHIP"
WATTAGE"1/20W"
TOLERANCE"1%"
VALUE"10K"
PACK_TYPE"0201LF"
CDS_LIB"pure_quanta"
PART_NUMBER"CS31001FE17";
"A"
$PN"1"60;
"B"
$PN"2"15;
%"Q_RES"
"2","(-1275,3700)","0","pure_quanta","I99";
;
LOCATION"R1397"
$SEC"1"
CDS_SEC"1"
PACK_TYPE"0201LF"
TOLERANCE"1%"
VALUE"1K"
MATERIAL"EMPTY"
WATTAGE"1/20W"
CDS_LIB"pure_quanta"
PART_NUMBER"CS21001FE07";
"A"
$PN"1"1;
"B"
$PN"2"60;
END.
